(kicad_pcb
	(version 20260206)
	(generator "pcbnew")
	(generator_version "10.0")
	(general
		(thickness 1.6)
		(legacy_teardrops no)
	)
	(paper "A4")
	(title_block
		(title "dpb — 14545-sa.0730WZS0815.brd")
		(comment 1 "Honey Badger (Wiwynn) / footprints 294-301 of 1066")
	)
	(layers
		(0 "F.Cu" signal "TOP")
		(4 "In1.Cu" signal "L2GND")
		(6 "In2.Cu" signal "L3")
		(8 "In3.Cu" signal "L4VCC")
		(10 "In4.Cu" signal "L5VCC")
		(12 "In5.Cu" signal "L6")
		(14 "In6.Cu" signal "L7GND")
		(2 "B.Cu" signal "BOTTOM")
		(9 "F.Adhes" user "F.Adhesive")
		(11 "B.Adhes" user "B.Adhesive")
		(13 "F.Paste" user "Package Geometry/Pastemask Top")
		(15 "B.Paste" user "Package Geometry/Pastemask Bottom")
		(5 "F.SilkS" user "Ref Des/Silkscreen Top")
		(7 "B.SilkS" user "Ref Des/Silkscreen Bottom")
		(1 "F.Mask" user "Board Geometry/Soldermask Top")
		(3 "B.Mask" user "Board Geometry/Soldermask Bottom")
		(17 "Dwgs.User" user "User.Drawings")
		(19 "Cmts.User" user "User.Comments")
		(21 "Eco1.User" user "User.Eco1")
		(23 "Eco2.User" user "User.Eco2")
		(25 "Edge.Cuts" user "Board Geometry/Outline")
		(27 "Margin" user)
		(31 "F.CrtYd" user "Package Geometry/Place Bound Top")
		(29 "B.CrtYd" user "Package Geometry/Place Bound Bottom")
		(35 "F.Fab" user "Ref Des/Assembly Top")
		(33 "B.Fab" user "Ref Des/Assembly Bottom")
	)
	(footprint ""
		(layer "F.Cu")
		(at 11.175746 -499.5037 180)
		(property "Reference" "PC30"
			(at 0 0 180)
			(layer "F.SilkS")
			(hide yes)
			(effects
				(font
					(size 1.27 1.27)
				)
			)
		)
		(property "Value" "SC1U10V2KX-1GP"
			(at 1.1811 -2.7051 180)
			(unlocked yes)
			(layer "F.Fab")
			(hide yes)
			(effects
				(font
					(size 1.016 1.016)
					(thickness 0.1524)
				)
			)
		)
		(property "Device Type" "C402H22"
			(at 1.1811 -4.2291 180)
			(unlocked yes)
			(layer "F.Fab")
			(hide yes)
			(effects
				(font
					(size 1.016 1.016)
					(thickness 0.1524)
				)
			)
		)
		(duplicate_pad_numbers_are_jumpers no)
		(fp_rect
			(start -0.4318 0.9525)
			(end 0.4318 -0.9525)
			(stroke
				(width 0)
				(type default)
			)
			(fill no)
			(layer "F.CrtYd")
		)
		(fp_rect
			(start -0.4318 0.9525)
			(end 0.4318 -0.9525)
			(stroke
				(width 0)
				(type default)
			)
			(fill no)
			(layer "F.Fab")
		)
		(pad "1" smd custom
			(at 0 -0.4445 180)
			(size 0.1524 0.1524)
			(layers "F.Cu" "F.Mask" "F.Paste")
			(net "P5VC_VREG")
			(options
				(clearance outline)
				(anchor circle)
			)
			(primitives
				(gr_poly
					(pts
						(arc
							(start 0.3048 -0.2032)
							(mid 0.275042 -0.275042)
							(end 0.2032 -0.3048)
						)
						(arc
							(start -0.2032 -0.3048)
							(mid -0.275042 -0.275042)
							(end -0.3048 -0.2032)
						)
						(arc
							(start -0.3048 0.2032)
							(mid -0.275042 0.275042)
							(end -0.2032 0.3048)
						)
						(arc
							(start 0.2032 0.3048)
							(mid 0.275042 0.275042)
							(end 0.3048 0.2032)
						)
					)
					(width 0)
					(fill yes)
				)
			)
		)
		(pad "2" smd custom
			(at 0 0.4445 180)
			(size 0.1524 0.1524)
			(layers "F.Cu" "F.Mask" "F.Paste")
			(net "GND")
			(options
				(clearance outline)
				(anchor circle)
			)
			(primitives
				(gr_poly
					(pts
						(arc
							(start 0.3048 -0.2032)
							(mid 0.275042 -0.275042)
							(end 0.2032 -0.3048)
						)
						(arc
							(start -0.2032 -0.3048)
							(mid -0.275042 -0.275042)
							(end -0.3048 -0.2032)
						)
						(arc
							(start -0.3048 0.2032)
							(mid -0.275042 0.275042)
							(end -0.2032 0.3048)
						)
						(arc
							(start 0.2032 0.3048)
							(mid 0.275042 0.275042)
							(end 0.3048 0.2032)
						)
					)
					(width 0)
					(fill yes)
				)
			)
		)
	)
	(footprint ""
		(layer "F.Cu")
		(at 62.610746 -185.8137)
		(property "Reference" "C239"
			(at 0 0 0)
			(layer "F.SilkS")
			(hide yes)
			(effects
				(font
					(size 1.27 1.27)
				)
			)
		)
		(property "Value" "SC10U25V6KX-1GP"
			(at -0.0762 -5.1308 0)
			(unlocked yes)
			(layer "F.Fab")
			(hide yes)
			(effects
				(font
					(size 1.016 1.016)
					(thickness 0.1524)
				)
			)
		)
		(property "Device Type" "C1206H71"
			(at -0.127 -6.6548 0)
			(unlocked yes)
			(layer "F.Fab")
			(hide yes)
			(effects
				(font
					(size 1.016 1.016)
					(thickness 0.1524)
				)
			)
		)
		(duplicate_pad_numbers_are_jumpers no)
		(fp_line
			(start -1.016 -2.2352)
			(end 1.016 -2.2352)
			(stroke
				(width 0.1524)
				(type default)
			)
			(layer "F.SilkS")
		)
		(fp_line
			(start -1.016 -0.8382)
			(end -1.016 -2.2352)
			(stroke
				(width 0.1524)
				(type default)
			)
			(layer "F.SilkS")
		)
		(fp_line
			(start -1.016 2.2352)
			(end -1.016 0.8382)
			(stroke
				(width 0.1524)
				(type default)
			)
			(layer "F.SilkS")
		)
		(fp_line
			(start 1.016 -2.2352)
			(end 1.016 -0.8382)
			(stroke
				(width 0.1524)
				(type default)
			)
			(layer "F.SilkS")
		)
		(fp_line
			(start 1.016 0.8382)
			(end 1.016 2.2352)
			(stroke
				(width 0.1524)
				(type default)
			)
			(layer "F.SilkS")
		)
		(fp_line
			(start 1.016 2.2352)
			(end -1.016 2.2352)
			(stroke
				(width 0.1524)
				(type default)
			)
			(layer "F.SilkS")
		)
		(fp_rect
			(start -1.0922 2.3114)
			(end 1.0922 -2.3114)
			(stroke
				(width 0)
				(type default)
			)
			(fill no)
			(layer "F.CrtYd")
		)
		(fp_poly
			(pts
				(xy 1.0922 -2.3114) (xy 1.0922 2.3114) (xy -1.0922 2.3114) (xy -1.0922 -2.3114)
			)
			(stroke
				(width 0)
				(type default)
			)
			(fill no)
			(layer "F.Fab")
		)
		(pad "1" smd rect
			(at 0 -1.397)
			(size 1.651 1.27)
			(layers "F.Cu" "F.Mask" "F.Paste")
			(net "P12V_HDD8")
		)
		(pad "2" smd rect
			(at 0 1.397)
			(size 1.651 1.27)
			(layers "F.Cu" "F.Mask" "F.Paste")
			(net "GND")
		)
	)
	(footprint ""
		(layer "F.Cu")
		(at 68.999608 -273.999706)
		(property "Reference" "H8"
			(at 0 0 0)
			(layer "F.SilkS")
			(hide yes)
			(effects
				(font
					(size 1.27 1.27)
				)
			)
		)
		(property "Value" "HOLE315R140"
			(at 0 -7.5692 0)
			(unlocked yes)
			(layer "F.Fab")
			(hide yes)
			(effects
				(font
					(size 1.016 1.016)
					(thickness 0.1524)
				)
			)
		)
		(property "Device Type" "HOLE315R140"
			(at 0 -9.0932 0)
			(unlocked yes)
			(layer "F.Fab")
			(hide yes)
			(effects
				(font
					(size 1.016 1.016)
					(thickness 0.1524)
				)
			)
		)
		(duplicate_pad_numbers_are_jumpers no)
		(fp_poly
			(pts
				(arc
					(start 4.3053 0)
					(mid -4.3053 0)
					(end 4.3053 0)
				)
			)
			(stroke
				(width 0)
				(type default)
			)
			(fill no)
			(layer "F.CrtYd")
		)
		(fp_poly
			(pts
				(arc
					(start 4.3053 0)
					(mid -4.3053 0)
					(end 4.3053 0)
				)
			)
			(stroke
				(width 0)
				(type default)
			)
			(fill no)
			(layer "F.Fab")
		)
		(pad "1" thru_hole circle
			(at 0.00127 0.00127)
			(size 8.001 8.001)
			(drill 3.556)
			(layers "*.Cu" "*.Mask")
			(remove_unused_layers no)
			(net "GND")
			(clearance -1.7145)
			(thermal_gap 0.3048)
			(padstack
				(mode front_inner_back)
				(layer "Inner"
					(shape circle)
					(size 3.9624 3.9624)
					(clearance 0.3048)
				)
				(layer "B.Cu"
					(shape circle)
					(size 8.001 8.001)
					(clearance -1.7145)
				)
			)
		)
	)
	(footprint ""
		(layer "F.Cu")
		(at 55.2704 -285.75 180)
		(property "Reference" "C220"
			(at 0 0 180)
			(layer "F.SilkS")
			(hide yes)
			(effects
				(font
					(size 1.27 1.27)
				)
			)
		)
		(property "Value" "SC1U16V3KX-5GP"
			(at 0 -2.8194 180)
			(unlocked yes)
			(layer "F.Fab")
			(hide yes)
			(effects
				(font
					(size 1.016 1.016)
					(thickness 0.1524)
				)
			)
		)
		(property "Device Type" "C603H36"
			(at 0 -4.3434 180)
			(unlocked yes)
			(layer "F.Fab")
			(hide yes)
			(effects
				(font
					(size 1.016 1.016)
					(thickness 0.1524)
				)
			)
		)
		(duplicate_pad_numbers_are_jumpers no)
		(fp_line
			(start 0.508 0)
			(end -0.508 0)
			(stroke
				(width 0.2032)
				(type default)
			)
			(layer "F.SilkS")
		)
		(fp_rect
			(start -0.5842 1.3335)
			(end 0.5842 -1.3335)
			(stroke
				(width 0)
				(type default)
			)
			(fill no)
			(layer "F.CrtYd")
		)
		(fp_rect
			(start -0.5842 1.3335)
			(end 0.5842 -1.3335)
			(stroke
				(width 0)
				(type default)
			)
			(fill no)
			(layer "F.Fab")
		)
		(pad "1" smd custom
			(at 0 -0.762 180)
			(size 0.2159 0.2159)
			(layers "F.Cu" "F.Mask" "F.Paste")
			(net "P5V_HDD7")
			(options
				(clearance outline)
				(anchor circle)
			)
			(primitives
				(gr_poly
					(pts
						(arc
							(start -0.3302 -0.4318)
							(mid -0.402042 -0.402042)
							(end -0.4318 -0.3302)
						)
						(arc
							(start -0.4318 0.3302)
							(mid -0.402042 0.402042)
							(end -0.3302 0.4318)
						)
						(arc
							(start 0.3302 0.4318)
							(mid 0.402042 0.402042)
							(end 0.4318 0.3302)
						)
						(arc
							(start 0.4318 -0.3302)
							(mid 0.402042 -0.402042)
							(end 0.3302 -0.4318)
						)
					)
					(width 0)
					(fill yes)
				)
			)
		)
		(pad "2" smd custom
			(at 0 0.762 180)
			(size 0.2159 0.2159)
			(layers "F.Cu" "F.Mask" "F.Paste")
			(net "GND")
			(options
				(clearance outline)
				(anchor circle)
			)
			(primitives
				(gr_poly
					(pts
						(arc
							(start -0.3302 -0.4318)
							(mid -0.402042 -0.402042)
							(end -0.4318 -0.3302)
						)
						(arc
							(start -0.4318 0.3302)
							(mid -0.402042 0.402042)
							(end -0.3302 0.4318)
						)
						(arc
							(start 0.3302 0.4318)
							(mid 0.402042 0.402042)
							(end 0.4318 0.3302)
						)
						(arc
							(start 0.4318 -0.3302)
							(mid 0.402042 -0.402042)
							(end 0.3302 -0.4318)
						)
					)
					(width 0)
					(fill yes)
				)
			)
		)
	)
	(footprint ""
		(layer "F.Cu")
		(at 33.893252 -166.25951 -90)
		(property "Reference" "C232"
			(at 0 0 270)
			(layer "F.SilkS")
			(hide yes)
			(effects
				(font
					(size 1.27 1.27)
				)
			)
		)
		(property "Value" "SCD01U50V2KX-1GP"
			(at 1.1811 -2.7051 270)
			(unlocked yes)
			(layer "F.Fab")
			(hide yes)
			(effects
				(font
					(size 1.016 1.016)
					(thickness 0.1524)
				)
			)
		)
		(property "Device Type" "C402H22"
			(at 1.1811 -4.2291 270)
			(unlocked yes)
			(layer "F.Fab")
			(hide yes)
			(effects
				(font
					(size 1.016 1.016)
					(thickness 0.1524)
				)
			)
		)
		(duplicate_pad_numbers_are_jumpers no)
		(fp_rect
			(start -0.4318 0.9525)
			(end 0.4318 -0.9525)
			(stroke
				(width 0)
				(type default)
			)
			(fill no)
			(layer "F.CrtYd")
		)
		(fp_rect
			(start -0.4318 0.9525)
			(end 0.4318 -0.9525)
			(stroke
				(width 0)
				(type default)
			)
			(fill no)
			(layer "F.Fab")
		)
		(pad "1" smd custom
			(at 0 -0.4445 270)
			(size 0.1524 0.1524)
			(layers "F.Cu" "F.Mask" "F.Paste")
			(net "SAS2X28_DRIVE_RX_N_B8")
			(options
				(clearance outline)
				(anchor circle)
			)
			(primitives
				(gr_poly
					(pts
						(arc
							(start 0.3048 -0.2032)
							(mid 0.275042 -0.275042)
							(end 0.2032 -0.3048)
						)
						(arc
							(start -0.2032 -0.3048)
							(mid -0.275042 -0.275042)
							(end -0.3048 -0.2032)
						)
						(arc
							(start -0.3048 0.2032)
							(mid -0.275042 0.275042)
							(end -0.2032 0.3048)
						)
						(arc
							(start 0.2032 0.3048)
							(mid 0.275042 0.275042)
							(end 0.3048 0.2032)
						)
					)
					(width 0)
					(fill yes)
				)
			)
		)
		(pad "2" smd custom
			(at 0 0.4445 270)
			(size 0.1524 0.1524)
			(layers "F.Cu" "F.Mask" "F.Paste")
			(net "SAS2X28_B_HDD8_RX_-")
			(options
				(clearance outline)
				(anchor circle)
			)
			(primitives
				(gr_poly
					(pts
						(arc
							(start 0.3048 -0.2032)
							(mid 0.275042 -0.275042)
							(end 0.2032 -0.3048)
						)
						(arc
							(start -0.2032 -0.3048)
							(mid -0.275042 -0.275042)
							(end -0.3048 -0.2032)
						)
						(arc
							(start -0.3048 0.2032)
							(mid -0.275042 0.275042)
							(end -0.2032 0.3048)
						)
						(arc
							(start 0.2032 0.3048)
							(mid 0.275042 0.275042)
							(end 0.3048 0.2032)
						)
					)
					(width 0)
					(fill yes)
				)
			)
		)
	)
	(footprint ""
		(layer "F.Cu")
		(at 33.527746 -433.0827 180)
		(property "Reference" "R463"
			(at 0 0 180)
			(layer "F.SilkS")
			(hide yes)
			(effects
				(font
					(size 1.27 1.27)
				)
			)
		)
		(property "Value" "4K7R2J-2-GP"
			(at 0.064008 -3.993896 180)
			(unlocked yes)
			(layer "F.Fab")
			(hide yes)
			(effects
				(font
					(size 1.016 1.016)
					(thickness 0.1524)
				)
			)
		)
		(property "Device Type" "R402H16"
			(at 0.064008 -5.517896 180)
			(unlocked yes)
			(layer "F.Fab")
			(hide yes)
			(effects
				(font
					(size 1.016 1.016)
					(thickness 0.1524)
				)
			)
		)
		(duplicate_pad_numbers_are_jumpers no)
		(fp_line
			(start 0.508 -0.9398)
			(end -0.508 -0.9398)
			(stroke
				(width 0.1524)
				(type default)
			)
			(layer "F.SilkS")
		)
		(fp_line
			(start -0.508 -0.9398)
			(end -0.508 0.9398)
			(stroke
				(width 0.1524)
				(type default)
			)
			(layer "F.SilkS")
		)
		(fp_rect
			(start -0.508 0.9398)
			(end 0.508 -0.9398)
			(stroke
				(width 0)
				(type default)
			)
			(fill no)
			(layer "F.CrtYd")
		)
		(fp_rect
			(start -0.508 0.9398)
			(end 0.508 -0.9398)
			(stroke
				(width 0)
				(type default)
			)
			(fill no)
			(layer "F.Fab")
		)
		(pad "1" smd custom
			(at 0 -0.4445 180)
			(size 0.1397 0.1397)
			(layers "F.Cu" "F.Mask" "F.Paste")
			(net "P3V3")
			(options
				(clearance outline)
				(anchor circle)
			)
			(primitives
				(gr_poly
					(pts
						(arc
							(start -0.1778 -0.2794)
							(mid -0.249642 -0.249642)
							(end -0.2794 -0.1778)
						)
						(arc
							(start -0.2794 0.1778)
							(mid -0.249642 0.249642)
							(end -0.1778 0.2794)
						)
						(arc
							(start 0.1778 0.2794)
							(mid 0.249642 0.249642)
							(end 0.2794 0.1778)
						)
						(arc
							(start 0.2794 -0.1778)
							(mid 0.249642 -0.249642)
							(end 0.1778 -0.2794)
						)
					)
					(width 0)
					(fill yes)
				)
			)
		)
		(pad "2" smd custom
			(at 0 0.4445 180)
			(size 0.1397 0.1397)
			(layers "F.Cu" "F.Mask" "F.Paste")
			(net "SAS_EXP_B_PWR10")
			(options
				(clearance outline)
				(anchor circle)
			)
			(primitives
				(gr_poly
					(pts
						(arc
							(start -0.1778 -0.2794)
							(mid -0.249642 -0.249642)
							(end -0.2794 -0.1778)
						)
						(arc
							(start -0.2794 0.1778)
							(mid -0.249642 0.249642)
							(end -0.1778 0.2794)
						)
						(arc
							(start 0.1778 0.2794)
							(mid 0.249642 0.249642)
							(end 0.2794 0.1778)
						)
						(arc
							(start 0.2794 -0.1778)
							(mid 0.249642 -0.249642)
							(end 0.1778 -0.2794)
						)
					)
					(width 0)
					(fill yes)
				)
			)
		)
	)
	(footprint ""
		(layer "F.Cu")
		(at 58.038746 -392.6967 90)
		(property "Reference" "R195"
			(at 0 0 90)
			(layer "F.SilkS")
			(hide yes)
			(effects
				(font
					(size 1.27 1.27)
				)
			)
		)
		(property "Value" "2R2010J-1-GP"
			(at 0.254 -8.0772 90)
			(unlocked yes)
			(layer "F.Fab")
			(hide yes)
			(effects
				(font
					(size 1.016 1.016)
					(thickness 0.1524)
				)
			)
		)
		(property "Device Type" "R2010H28"
			(at 0.254 -9.6774 90)
			(unlocked yes)
			(layer "F.Fab")
			(hide yes)
			(effects
				(font
					(size 1.016 1.016)
					(thickness 0.1524)
				)
			)
		)
		(duplicate_pad_numbers_are_jumpers no)
		(fp_line
			(start 1.651 -3.302)
			(end -1.651 -3.302)
			(stroke
				(width 0.1524)
				(type default)
			)
			(layer "F.SilkS")
		)
		(fp_line
			(start -1.651 -3.302)
			(end -1.651 3.302)
			(stroke
				(width 0.1524)
				(type default)
			)
			(layer "F.SilkS")
		)
		(fp_line
			(start 1.651 3.302)
			(end 1.651 -3.302)
			(stroke
				(width 0.1524)
				(type default)
			)
			(layer "F.SilkS")
		)
		(fp_line
			(start -1.651 3.302)
			(end 1.651 3.302)
			(stroke
				(width 0.1524)
				(type default)
			)
			(layer "F.SilkS")
		)
		(fp_rect
			(start -1.7272 -3.3782)
			(end 1.7272 3.3782)
			(stroke
				(width 0)
				(type default)
			)
			(fill no)
			(layer "F.CrtYd")
		)
		(fp_poly
			(pts
				(xy 1.7272 3.3782) (xy 1.7272 -3.3782) (xy -1.7272 -3.3782) (xy -1.7272 3.3782)
			)
			(stroke
				(width 0)
				(type default)
			)
			(fill no)
			(layer "F.Fab")
		)
		(pad "1" smd rect
			(at 0 -2.3495 90)
			(size 2.794 1.143)
			(layers "F.Cu" "F.Mask" "F.Paste")
			(net "12V_PRE_6")
		)
		(pad "2" smd rect
			(at 0 2.3495 90)
			(size 2.794 1.143)
			(layers "F.Cu" "F.Mask" "F.Paste")
			(net "P12V_HDD6")
		)
	)
	(footprint ""
		(layer "F.Cu")
		(at 54.2544 -497.7384 180)
		(property "Reference" "C195"
			(at 0 0 180)
			(layer "F.SilkS")
			(hide yes)
			(effects
				(font
					(size 1.27 1.27)
				)
			)
		)
		(property "Value" "SC1U25V3KX-1-GP"
			(at 0 -2.8194 180)
			(unlocked yes)
			(layer "F.Fab")
			(hide yes)
			(effects
				(font
					(size 1.016 1.016)
					(thickness 0.1524)
				)
			)
		)
		(property "Device Type" "C603H36"
			(at 0 -4.3434 180)
			(unlocked yes)
			(layer "F.Fab")
			(hide yes)
			(effects
				(font
					(size 1.016 1.016)
					(thickness 0.1524)
				)
			)
		)
		(duplicate_pad_numbers_are_jumpers no)
		(fp_line
			(start 0.508 0)
			(end -0.508 0)
			(stroke
				(width 0.2032)
				(type default)
			)
			(layer "F.SilkS")
		)
		(fp_rect
			(start -0.5842 1.3335)
			(end 0.5842 -1.3335)
			(stroke
				(width 0)
				(type default)
			)
			(fill no)
			(layer "F.CrtYd")
		)
		(fp_rect
			(start -0.5842 1.3335)
			(end 0.5842 -1.3335)
			(stroke
				(width 0)
				(type default)
			)
			(fill no)
			(layer "F.Fab")
		)
		(pad "1" smd custom
			(at 0 -0.762 180)
			(size 0.2159 0.2159)
			(layers "F.Cu" "F.Mask" "F.Paste")
			(net "P12V_HDD5")
			(options
				(clearance outline)
				(anchor circle)
			)
			(primitives
				(gr_poly
					(pts
						(arc
							(start -0.3302 -0.4318)
							(mid -0.402042 -0.402042)
							(end -0.4318 -0.3302)
						)
						(arc
							(start -0.4318 0.3302)
							(mid -0.402042 0.402042)
							(end -0.3302 0.4318)
						)
						(arc
							(start 0.3302 0.4318)
							(mid 0.402042 0.402042)
							(end 0.4318 0.3302)
						)
						(arc
							(start 0.4318 -0.3302)
							(mid 0.402042 -0.402042)
							(end 0.3302 -0.4318)
						)
					)
					(width 0)
					(fill yes)
				)
			)
		)
		(pad "2" smd custom
			(at 0 0.762 180)
			(size 0.2159 0.2159)
			(layers "F.Cu" "F.Mask" "F.Paste")
			(net "GND")
			(options
				(clearance outline)
				(anchor circle)
			)
			(primitives
				(gr_poly
					(pts
						(arc
							(start -0.3302 -0.4318)
							(mid -0.402042 -0.402042)
							(end -0.4318 -0.3302)
						)
						(arc
							(start -0.4318 0.3302)
							(mid -0.402042 0.402042)
							(end -0.3302 0.4318)
						)
						(arc
							(start 0.3302 0.4318)
							(mid 0.402042 0.402042)
							(end 0.4318 0.3302)
						)
						(arc
							(start 0.4318 -0.3302)
							(mid 0.402042 -0.402042)
							(end 0.3302 -0.4318)
						)
					)
					(width 0)
					(fill yes)
				)
			)
		)
	)
)
